#ISCELL
  mstr_misc dns *
  *
#ISCELL
  pure_quanta quanta_title_block_c *
  *
#CELL
  pure_quanta q_res *
  page77_i1
#ISCELL
  pure_quanta_power universal_gnd *
  page77_i10
#CELL
  pure_quanta q_cap *
  page77_i11
#ISCELL
  pure_quanta_power universal_power *
  page77_i12
#ISCELL
  standard offpage *
  page77_i13
#ISCELL
  standard offpage *
  page77_i14
#CELL
  pure_quanta sn74lvc2g07dckr *
  page77_i15
#ISCELL
  standard offpage *
  page77_i16
#ISCELL
  standard offpage *
  page77_i17
#CELL
  pure_quanta q_cap *
  page77_i19
#ISCELL
  pure_quanta_power gnd *
  page77_i2
#ISCELL
  pure_quanta_power universal_gnd *
  page77_i20
#CELL
  pure_quanta sn74lvc2g07dckr *
  page77_i21
#ISCELL
  pure_quanta_power universal_gnd *
  page77_i22
#ISCELL
  pure_quanta_power universal_power *
  page77_i23
#ISCELL
  standard offpage *
  page77_i3
#ISCELL
  standard offpage *
  page77_i4
#CELL
  pure_quanta q_res *
  page77_i5
#ISCELL
  pure_quanta_power gnd *
  page77_i6
#ISCELL
  pure_quanta_power universal_gnd *
  page77_i9
